FILE_TYPE = MACRO_DRAWING;
SET COLOR_WIRE YELLOW;
SET COLOR_PROP ORANGE;
SET COLOR_DOT WHITE;
SET COLOR_ARC YELLOW;
SET COLOR_BODY GREEN;
SET COLOR_NOTE PURPLE;
SET PROP_DISPLAY VALUE;
SET PAGE_NUMBER P8;
SET PATH_NUMBER P0;
FORCEADD QUANTA_TITLE_BLOCK_C..1
(5875 -1675);
FORCEPROP 0 LAST CDS_CON_LAST_MODIFIED Fri Aug 25 17:25:35 2023
J 0
(3990 -1660);
DISPLAY INVISIBLE (3990 -1660);
FORCEPROP 2 LAST Q_DEPT 
J 1
(2112 -1626);
DISPLAY 1.957447 (2112 -1626);
PAINT GREEN (2112 -1626);
FORCEPROP 1 LAST CUSTOM_TXT_CDS <CON_LAST_MODIFIED>
J 0
(3990 -1660);
DISPLAY 0.978723 (3990 -1660);
FORCEPROP 2 LAST CUSTOM_TXT_CDS <XR_PAGE_TITLE>
J 0
(-2015 3575);
DISPLAY 0.638298 (-2015 3575);
PAINT PINK (-2015 3575);
DISPLAY INVISIBLE (-2015 3575);
FORCEPROP 1 LAST CUSTOM_TXT_CDS <NAME_2>
J 0
(2700 -1625);
FORCEPROP 1 LAST CUSTOM_TXT_CDS <NAME_1>
J 0
(2700 -1500);
FORCEPROP 1 LAST CUSTOM_TXT_CDS <Q_NUMBER>
J 0
(4472 -1572);
DISPLAY 1.212766 (4472 -1572);
FORCEPROP 1 LAST CUSTOM_TXT_CDS <Q_PROJ>
J 0
(3493 -1573);
DISPLAY 1.212766 (3493 -1573);
FORCEPROP 1 LAST CUSTOM_TXT_CDS <Q_REV>
J 0
(5691 -1572);
DISPLAY 1.212766 (5691 -1572);
FORCEPROP 1 LAST CUSTOM_TXT_CDS <CON_PAGE_NUM> OF <CON_TOTAL_PAGES>
J 0
(5429 -1657);
DISPLAY 0.978723 (5429 -1657);
FORCEPROP 1 LAST Q_TITLE POWER SEQUENCE
J 0
(-3491 -1649);
DISPLAY 2.446809 (-3491 -1649);
PAINT GREEN (-3491 -1649);
FORCEPROP 2 LAST PAGE_BORDER TRUE
J 0
(-2015 3575);
DISPLAY 0.638298 (-2015 3575);
PAINT PINK (-2015 3575);
DISPLAY INVISIBLE (-2015 3575);
FORCEPROP 1 LAST CDS_LMAN_SYM_OUTLINE -9475,6775,100,-125
J 0
(5875 -1675);
DISPLAY 0.468085 (5875 -1675);
PAINT GREEN (5875 -1675);
DISPLAY INVISIBLE (5875 -1675);
FORCEPROP 2 LAST CDS_LIB pure_quanta
J 0
(5875 -1675);
DISPLAY INVISIBLE (5875 -1675);
FORCEPROP 1 LAST COMMENT_BODY TRUE
J 0
(5887 -1688);
DISPLAY 0.978723 (5887 -1688);
PAINT PEACH (5887 -1688);
DISPLAY INVISIBLE (5887 -1688);
FORCEPROP 2 LAST CDS_XR_PAGE_TITLE CR-8 : @SCM_LIB.SCM(SCH_1):PAGE8
J 0
(-2015 3575);
DISPLAY 0.638298 (-2015 3575);
PAINT PINK (-2015 3575);
DISPLAY INVISIBLE (-2015 3575);
FORCENOTE
$CDS_IMAGE|F0T_Power_Sequence_20220323-Sequence.jpg|7689|6381
(1125 1775) 0;
DISPLAY LEFT (1125 1775);
QUIT
